(kicad_pcb
	(version 20260206)
	(generator "pcbnew")
	(generator_version "10.0")
	(general
		(thickness 1.6)
		(legacy_teardrops no)
	)
	(paper "A4")
	(title_block
		(title "panther-plus-userver — 13130-1b_20150205.brd")
		(comment 1 "Honey Badger (Wiwynn) / footprints 1481-1488 of 1509")
	)
	(layers
		(0 "F.Cu" signal "TOP")
		(4 "In1.Cu" signal "L2")
		(6 "In2.Cu" signal "L3")
		(8 "In3.Cu" signal "L4")
		(10 "In4.Cu" signal "L5")
		(12 "In5.Cu" signal "L6")
		(14 "In6.Cu" signal "L7")
		(16 "In7.Cu" signal "L8")
		(18 "In8.Cu" signal "L9")
		(20 "In9.Cu" signal "L10")
		(22 "In10.Cu" signal "L11")
		(2 "B.Cu" signal "BOTTOM")
		(9 "F.Adhes" user "F.Adhesive")
		(11 "B.Adhes" user "B.Adhesive")
		(13 "F.Paste" user "Package Geometry/Pastemask Top")
		(15 "B.Paste" user "Package Geometry/Pastemask Bottom")
		(5 "F.SilkS" user "Ref Des/Silkscreen Top")
		(7 "B.SilkS" user "Ref Des/Silkscreen Bottom")
		(1 "F.Mask" user "Board Geometry/Soldermask Top")
		(3 "B.Mask" user "Board Geometry/Soldermask Bottom")
		(17 "Dwgs.User" user "User.Drawings")
		(19 "Cmts.User" user "User.Comments")
		(21 "Eco1.User" user "User.Eco1")
		(23 "Eco2.User" user "User.Eco2")
		(25 "Edge.Cuts" user "Board Geometry/Outline")
		(27 "Margin" user)
		(31 "F.CrtYd" user "Package Geometry/Place Bound Top")
		(29 "B.CrtYd" user "Package Geometry/Place Bound Bottom")
		(35 "F.Fab" user "Ref Des/Assembly Top")
		(33 "B.Fab" user "Ref Des/Assembly Bottom")
	)
	(footprint ""
		(layer "B.Cu")
		(at 53.467 -17.272 -90)
		(property "Reference" "C304"
			(at 0 0 90)
			(layer "B.SilkS")
			(hide yes)
			(effects
				(font
					(size 1.27 1.27)
				)
				(justify mirror)
			)
		)
		(property "Value" "SCD1U16V2KX-3GP"
			(at -1.8923 -1.2065 270)
			(unlocked yes)
			(layer "B.Fab")
			(hide yes)
			(effects
				(font
					(size 1.016 1.016)
					(thickness 0.1524)
				)
				(justify mirror)
			)
		)
		(property "Device Type" "C402H22"
			(at -1.8923 -2.7305 270)
			(unlocked yes)
			(layer "B.Fab")
			(hide yes)
			(effects
				(font
					(size 1.016 1.016)
					(thickness 0.1524)
				)
				(justify mirror)
			)
		)
		(duplicate_pad_numbers_are_jumpers no)
		(fp_rect
			(start 0.381 0.7366)
			(end -0.381 -0.7366)
			(stroke
				(width 0)
				(type default)
			)
			(fill no)
			(layer "B.CrtYd")
		)
		(fp_rect
			(start 0.381 0.7366)
			(end -0.381 -0.7366)
			(stroke
				(width 0)
				(type default)
			)
			(fill no)
			(layer "B.Fab")
		)
		(pad "1" smd custom
			(at 0 -0.4572 90)
			(size 0.1143 0.1143)
			(layers "B.Cu" "B.Mask" "B.Paste")
			(net "P3V3")
			(options
				(clearance outline)
				(anchor circle)
			)
			(primitives
				(gr_poly
					(pts
						(arc
							(start -0.254 0.1778)
							(mid -0.239121 0.213721)
							(end -0.2032 0.2286)
						)
						(arc
							(start 0.2032 0.2286)
							(mid 0.239121 0.213721)
							(end 0.254 0.1778)
						)
						(arc
							(start 0.254 -0.1778)
							(mid 0.239121 -0.213721)
							(end 0.2032 -0.2286)
						)
						(arc
							(start -0.2032 -0.2286)
							(mid -0.239121 -0.213721)
							(end -0.254 -0.1778)
						)
					)
					(width 0)
					(fill yes)
				)
			)
		)
		(pad "2" smd custom
			(at 0 0.4572 90)
			(size 0.1143 0.1143)
			(layers "B.Cu" "B.Mask" "B.Paste")
			(net "GND")
			(options
				(clearance outline)
				(anchor circle)
			)
			(primitives
				(gr_poly
					(pts
						(arc
							(start -0.254 0.1778)
							(mid -0.239121 0.213721)
							(end -0.2032 0.2286)
						)
						(arc
							(start 0.2032 0.2286)
							(mid 0.239121 0.213721)
							(end 0.254 0.1778)
						)
						(arc
							(start 0.254 -0.1778)
							(mid 0.239121 -0.213721)
							(end 0.2032 -0.2286)
						)
						(arc
							(start -0.2032 -0.2286)
							(mid -0.239121 -0.213721)
							(end -0.254 -0.1778)
						)
					)
					(width 0)
					(fill yes)
				)
			)
		)
	)
	(footprint ""
		(layer "B.Cu")
		(at 131.445 -56.388 180)
		(property "Reference" "PC142"
			(at 0 0 0)
			(layer "B.SilkS")
			(hide yes)
			(effects
				(font
					(size 1.27 1.27)
				)
				(justify mirror)
			)
		)
		(property "Value" "SC10U6D3V3MX-GP"
			(at 0 -2.8194 180)
			(unlocked yes)
			(layer "B.Fab")
			(hide yes)
			(effects
				(font
					(size 1.016 1.016)
					(thickness 0.1524)
				)
				(justify mirror)
			)
		)
		(property "Device Type" "C603H38"
			(at 0 -4.3434 180)
			(unlocked yes)
			(layer "B.Fab")
			(hide yes)
			(effects
				(font
					(size 1.016 1.016)
					(thickness 0.1524)
				)
				(justify mirror)
			)
		)
		(duplicate_pad_numbers_are_jumpers no)
		(fp_line
			(start 0.4064 0)
			(end -0.4064 0)
			(stroke
				(width 0.2286)
				(type default)
			)
			(layer "B.SilkS")
		)
		(fp_rect
			(start 0.635 1.1811)
			(end -0.635 -1.1811)
			(stroke
				(width 0)
				(type default)
			)
			(fill no)
			(layer "B.CrtYd")
		)
		(fp_rect
			(start 0.635 1.1811)
			(end -0.635 -1.1811)
			(stroke
				(width 0)
				(type default)
			)
			(fill no)
			(layer "B.Fab")
		)
		(pad "1" smd custom
			(at 0 -0.6604)
			(size 0.19685 0.19685)
			(layers "B.Cu" "B.Mask" "B.Paste")
			(net "GND")
			(options
				(clearance outline)
				(anchor circle)
			)
			(primitives
				(gr_poly
					(pts
						(arc
							(start 0.508 0.2921)
							(mid 0.478242 0.363942)
							(end 0.4064 0.3937)
						)
						(arc
							(start -0.4064 0.3937)
							(mid -0.478242 0.363942)
							(end -0.508 0.2921)
						)
						(arc
							(start -0.508 -0.2921)
							(mid -0.478242 -0.363942)
							(end -0.4064 -0.3937)
						)
						(arc
							(start 0.4064 -0.3937)
							(mid 0.478242 -0.363942)
							(end 0.508 -0.2921)
						)
					)
					(width 0)
					(fill yes)
				)
			)
		)
		(pad "2" smd custom
			(at 0 0.6604)
			(size 0.19685 0.19685)
			(layers "B.Cu" "B.Mask" "B.Paste")
			(net "PV_VTT_DDR_A")
			(options
				(clearance outline)
				(anchor circle)
			)
			(primitives
				(gr_poly
					(pts
						(arc
							(start 0.508 0.2921)
							(mid 0.478242 0.363942)
							(end 0.4064 0.3937)
						)
						(arc
							(start -0.4064 0.3937)
							(mid -0.478242 0.363942)
							(end -0.508 0.2921)
						)
						(arc
							(start -0.508 -0.2921)
							(mid -0.478242 -0.363942)
							(end -0.4064 -0.3937)
						)
						(arc
							(start 0.4064 -0.3937)
							(mid 0.478242 -0.363942)
							(end 0.508 -0.2921)
						)
					)
					(width 0)
					(fill yes)
				)
			)
		)
	)
	(footprint ""
		(layer "B.Cu")
		(at 43.942 -54.102 90)
		(property "Reference" "R126"
			(at 0 0 90)
			(layer "B.SilkS")
			(hide yes)
			(effects
				(font
					(size 1.27 1.27)
				)
				(justify mirror)
			)
		)
		(property "Value" "0R2J-2-GP"
			(at -1.7907 -1.1176 90)
			(unlocked yes)
			(layer "B.Fab")
			(hide yes)
			(effects
				(font
					(size 1.016 1.016)
					(thickness 0.1524)
				)
				(justify mirror)
			)
		)
		(property "Device Type" "R402H16"
			(at -1.7907 -2.6416 90)
			(unlocked yes)
			(layer "B.Fab")
			(hide yes)
			(effects
				(font
					(size 1.016 1.016)
					(thickness 0.1524)
				)
				(justify mirror)
			)
		)
		(duplicate_pad_numbers_are_jumpers no)
		(fp_rect
			(start 0.381 0.8382)
			(end -0.381 -0.8382)
			(stroke
				(width 0)
				(type default)
			)
			(fill no)
			(layer "B.CrtYd")
		)
		(fp_rect
			(start 0.381 0.8382)
			(end -0.381 -0.8382)
			(stroke
				(width 0)
				(type default)
			)
			(fill no)
			(layer "B.Fab")
		)
		(pad "1" smd custom
			(at 0 -0.4318 270)
			(size 0.127 0.127)
			(layers "B.Cu" "B.Mask" "B.Paste")
			(net "CLKGEN_VSEL_PCI")
			(options
				(clearance outline)
				(anchor circle)
			)
			(primitives
				(gr_poly
					(pts
						(arc
							(start -0.2032 0.2794)
							(mid -0.239121 0.264521)
							(end -0.254 0.2286)
						)
						(arc
							(start -0.254 -0.2286)
							(mid -0.239121 -0.264521)
							(end -0.2032 -0.2794)
						)
						(arc
							(start 0.2032 -0.2794)
							(mid 0.239121 -0.264521)
							(end 0.254 -0.2286)
						)
						(arc
							(start 0.254 0.2286)
							(mid 0.239121 0.264521)
							(end 0.2032 0.2794)
						)
					)
					(width 0)
					(fill yes)
				)
			)
		)
		(pad "2" smd custom
			(at 0 0.4318 270)
			(size 0.127 0.127)
			(layers "B.Cu" "B.Mask" "B.Paste")
			(net "GND")
			(options
				(clearance outline)
				(anchor circle)
			)
			(primitives
				(gr_poly
					(pts
						(arc
							(start -0.2032 0.2794)
							(mid -0.239121 0.264521)
							(end -0.254 0.2286)
						)
						(arc
							(start -0.254 -0.2286)
							(mid -0.239121 -0.264521)
							(end -0.2032 -0.2794)
						)
						(arc
							(start 0.2032 -0.2794)
							(mid 0.239121 -0.264521)
							(end 0.254 -0.2286)
						)
						(arc
							(start 0.254 0.2286)
							(mid 0.239121 0.264521)
							(end 0.2032 0.2794)
						)
					)
					(width 0)
					(fill yes)
				)
			)
		)
	)
	(footprint ""
		(layer "B.Cu")
		(at 8.509 -25.146 -90)
		(property "Reference" "PC89"
			(at 0 0 90)
			(layer "B.SilkS")
			(hide yes)
			(effects
				(font
					(size 1.27 1.27)
				)
				(justify mirror)
			)
		)
		(property "Value" "SC1U16V2KX-GP"
			(at -1.8923 -1.2065 270)
			(unlocked yes)
			(layer "B.Fab")
			(hide yes)
			(effects
				(font
					(size 1.016 1.016)
					(thickness 0.1524)
				)
				(justify mirror)
			)
		)
		(property "Device Type" "C402H22"
			(at -1.8923 -2.7305 270)
			(unlocked yes)
			(layer "B.Fab")
			(hide yes)
			(effects
				(font
					(size 1.016 1.016)
					(thickness 0.1524)
				)
				(justify mirror)
			)
		)
		(duplicate_pad_numbers_are_jumpers no)
		(fp_rect
			(start 0.381 0.7366)
			(end -0.381 -0.7366)
			(stroke
				(width 0)
				(type default)
			)
			(fill no)
			(layer "B.CrtYd")
		)
		(fp_rect
			(start 0.381 0.7366)
			(end -0.381 -0.7366)
			(stroke
				(width 0)
				(type default)
			)
			(fill no)
			(layer "B.Fab")
		)
		(pad "1" smd custom
			(at 0 -0.4572 90)
			(size 0.1143 0.1143)
			(layers "B.Cu" "B.Mask" "B.Paste")
			(net "P1V0_VREG")
			(options
				(clearance outline)
				(anchor circle)
			)
			(primitives
				(gr_poly
					(pts
						(arc
							(start -0.254 0.1778)
							(mid -0.239121 0.213721)
							(end -0.2032 0.2286)
						)
						(arc
							(start 0.2032 0.2286)
							(mid 0.239121 0.213721)
							(end 0.254 0.1778)
						)
						(arc
							(start 0.254 -0.1778)
							(mid 0.239121 -0.213721)
							(end 0.2032 -0.2286)
						)
						(arc
							(start -0.2032 -0.2286)
							(mid -0.239121 -0.213721)
							(end -0.254 -0.1778)
						)
					)
					(width 0)
					(fill yes)
				)
			)
		)
		(pad "2" smd custom
			(at 0 0.4572 90)
			(size 0.1143 0.1143)
			(layers "B.Cu" "B.Mask" "B.Paste")
			(net "GND")
			(options
				(clearance outline)
				(anchor circle)
			)
			(primitives
				(gr_poly
					(pts
						(arc
							(start -0.254 0.1778)
							(mid -0.239121 0.213721)
							(end -0.2032 0.2286)
						)
						(arc
							(start 0.2032 0.2286)
							(mid 0.239121 0.213721)
							(end 0.254 0.1778)
						)
						(arc
							(start 0.254 -0.1778)
							(mid 0.239121 -0.213721)
							(end 0.2032 -0.2286)
						)
						(arc
							(start -0.2032 -0.2286)
							(mid -0.239121 -0.213721)
							(end -0.254 -0.1778)
						)
					)
					(width 0)
					(fill yes)
				)
			)
		)
	)
	(footprint ""
		(layer "B.Cu")
		(at 81.28 -27.051 90)
		(property "Reference" "R409"
			(at 0 0 90)
			(layer "B.SilkS")
			(hide yes)
			(effects
				(font
					(size 1.27 1.27)
				)
				(justify mirror)
			)
		)
		(property "Value" "4K7R2F-GP"
			(at -1.7907 -1.1176 90)
			(unlocked yes)
			(layer "B.Fab")
			(hide yes)
			(effects
				(font
					(size 1.016 1.016)
					(thickness 0.1524)
				)
				(justify mirror)
			)
		)
		(property "Device Type" "R402H16"
			(at -1.7907 -2.6416 90)
			(unlocked yes)
			(layer "B.Fab")
			(hide yes)
			(effects
				(font
					(size 1.016 1.016)
					(thickness 0.1524)
				)
				(justify mirror)
			)
		)
		(duplicate_pad_numbers_are_jumpers no)
		(fp_rect
			(start 0.381 0.8382)
			(end -0.381 -0.8382)
			(stroke
				(width 0)
				(type default)
			)
			(fill no)
			(layer "B.CrtYd")
		)
		(fp_rect
			(start 0.381 0.8382)
			(end -0.381 -0.8382)
			(stroke
				(width 0)
				(type default)
			)
			(fill no)
			(layer "B.Fab")
		)
		(pad "1" smd custom
			(at 0 -0.4318 270)
			(size 0.127 0.127)
			(layers "B.Cu" "B.Mask" "B.Paste")
			(net "P3V3_CPU")
			(options
				(clearance outline)
				(anchor circle)
			)
			(primitives
				(gr_poly
					(pts
						(arc
							(start -0.2032 0.2794)
							(mid -0.239121 0.264521)
							(end -0.254 0.2286)
						)
						(arc
							(start -0.254 -0.2286)
							(mid -0.239121 -0.264521)
							(end -0.2032 -0.2794)
						)
						(arc
							(start 0.2032 -0.2794)
							(mid 0.239121 -0.264521)
							(end 0.254 -0.2286)
						)
						(arc
							(start 0.254 0.2286)
							(mid 0.239121 0.264521)
							(end 0.2032 0.2794)
						)
					)
					(width 0)
					(fill yes)
				)
			)
		)
		(pad "2" smd custom
			(at 0 0.4318 270)
			(size 0.127 0.127)
			(layers "B.Cu" "B.Mask" "B.Paste")
			(net "BD_REV_2")
			(options
				(clearance outline)
				(anchor circle)
			)
			(primitives
				(gr_poly
					(pts
						(arc
							(start -0.2032 0.2794)
							(mid -0.239121 0.264521)
							(end -0.254 0.2286)
						)
						(arc
							(start -0.254 -0.2286)
							(mid -0.239121 -0.264521)
							(end -0.2032 -0.2794)
						)
						(arc
							(start 0.2032 -0.2794)
							(mid 0.239121 -0.264521)
							(end 0.254 -0.2286)
						)
						(arc
							(start 0.254 0.2286)
							(mid 0.239121 0.264521)
							(end 0.2032 0.2794)
						)
					)
					(width 0)
					(fill yes)
				)
			)
		)
	)
	(footprint ""
		(layer "B.Cu")
		(at 39.6494 -46.863)
		(property "Reference" "C68"
			(at 0 0 0)
			(layer "B.SilkS")
			(hide yes)
			(effects
				(font
					(size 1.27 1.27)
				)
				(justify mirror)
			)
		)
		(property "Value" "SC10U6D3V3MX-GP"
			(at 0.0254 -2.0193 0)
			(unlocked yes)
			(layer "B.Fab")
			(hide yes)
			(effects
				(font
					(size 1.016 1.016)
					(thickness 0.1524)
				)
				(justify mirror)
			)
		)
		(property "Device Type" "C603H38"
			(at 0.0254 -3.5433 0)
			(unlocked yes)
			(layer "B.Fab")
			(hide yes)
			(effects
				(font
					(size 1.016 1.016)
					(thickness 0.1524)
				)
				(justify mirror)
			)
		)
		(duplicate_pad_numbers_are_jumpers no)
		(fp_line
			(start 0.4064 0)
			(end -0.4064 0)
			(stroke
				(width 0.2286)
				(type default)
			)
			(layer "B.SilkS")
		)
		(fp_rect
			(start 0.635 1.1811)
			(end -0.635 -1.1811)
			(stroke
				(width 0)
				(type default)
			)
			(fill no)
			(layer "B.CrtYd")
		)
		(fp_rect
			(start 0.635 1.1811)
			(end -0.635 -1.1811)
			(stroke
				(width 0)
				(type default)
			)
			(fill no)
			(layer "B.Fab")
		)
		(pad "1" smd custom
			(at 0 -0.6604 180)
			(size 0.19685 0.19685)
			(layers "B.Cu" "B.Mask" "B.Paste")
			(net "P3V3_CLK_XTAL")
			(options
				(clearance outline)
				(anchor circle)
			)
			(primitives
				(gr_poly
					(pts
						(arc
							(start 0.508 0.2921)
							(mid 0.478242 0.363942)
							(end 0.4064 0.3937)
						)
						(arc
							(start -0.4064 0.3937)
							(mid -0.478242 0.363942)
							(end -0.508 0.2921)
						)
						(arc
							(start -0.508 -0.2921)
							(mid -0.478242 -0.363942)
							(end -0.4064 -0.3937)
						)
						(arc
							(start 0.4064 -0.3937)
							(mid 0.478242 -0.363942)
							(end 0.508 -0.2921)
						)
					)
					(width 0)
					(fill yes)
				)
			)
		)
		(pad "2" smd custom
			(at 0 0.6604 180)
			(size 0.19685 0.19685)
			(layers "B.Cu" "B.Mask" "B.Paste")
			(net "GND")
			(options
				(clearance outline)
				(anchor circle)
			)
			(primitives
				(gr_poly
					(pts
						(arc
							(start 0.508 0.2921)
							(mid 0.478242 0.363942)
							(end 0.4064 0.3937)
						)
						(arc
							(start -0.4064 0.3937)
							(mid -0.478242 0.363942)
							(end -0.508 0.2921)
						)
						(arc
							(start -0.508 -0.2921)
							(mid -0.478242 -0.363942)
							(end -0.4064 -0.3937)
						)
						(arc
							(start 0.4064 -0.3937)
							(mid 0.478242 -0.363942)
							(end 0.508 -0.2921)
						)
					)
					(width 0)
					(fill yes)
				)
			)
		)
	)
	(footprint ""
		(layer "B.Cu")
		(at 142.748 -45.466 -90)
		(property "Reference" "C192"
			(at 0 0 90)
			(layer "B.SilkS")
			(hide yes)
			(effects
				(font
					(size 1.27 1.27)
				)
				(justify mirror)
			)
		)
		(property "Value" "SCD1U10V2KX-5GP"
			(at -1.1811 -2.7051 270)
			(unlocked yes)
			(layer "B.Fab")
			(hide yes)
			(effects
				(font
					(size 1.016 1.016)
					(thickness 0.1524)
				)
				(justify mirror)
			)
		)
		(property "Device Type" "C402H22"
			(at -1.1811 -4.2291 270)
			(unlocked yes)
			(layer "B.Fab")
			(hide yes)
			(effects
				(font
					(size 1.016 1.016)
					(thickness 0.1524)
				)
				(justify mirror)
			)
		)
		(duplicate_pad_numbers_are_jumpers no)
		(fp_rect
			(start 0.381 0.7366)
			(end -0.381 -0.7366)
			(stroke
				(width 0)
				(type default)
			)
			(fill no)
			(layer "B.CrtYd")
		)
		(fp_rect
			(start 0.381 0.7366)
			(end -0.381 -0.7366)
			(stroke
				(width 0)
				(type default)
			)
			(fill no)
			(layer "B.Fab")
		)
		(pad "1" smd custom
			(at 0 -0.4572 90)
			(size 0.1143 0.1143)
			(layers "B.Cu" "B.Mask" "B.Paste")
			(net "P3V3_STBY")
			(options
				(clearance outline)
				(anchor circle)
			)
			(primitives
				(gr_poly
					(pts
						(arc
							(start -0.254 0.1778)
							(mid -0.239121 0.213721)
							(end -0.2032 0.2286)
						)
						(arc
							(start 0.2032 0.2286)
							(mid 0.239121 0.213721)
							(end 0.254 0.1778)
						)
						(arc
							(start 0.254 -0.1778)
							(mid 0.239121 -0.213721)
							(end 0.2032 -0.2286)
						)
						(arc
							(start -0.2032 -0.2286)
							(mid -0.239121 -0.213721)
							(end -0.254 -0.1778)
						)
					)
					(width 0)
					(fill yes)
				)
			)
		)
		(pad "2" smd custom
			(at 0 0.4572 90)
			(size 0.1143 0.1143)
			(layers "B.Cu" "B.Mask" "B.Paste")
			(net "GND")
			(options
				(clearance outline)
				(anchor circle)
			)
			(primitives
				(gr_poly
					(pts
						(arc
							(start -0.254 0.1778)
							(mid -0.239121 0.213721)
							(end -0.2032 0.2286)
						)
						(arc
							(start 0.2032 0.2286)
							(mid 0.239121 0.213721)
							(end 0.254 0.1778)
						)
						(arc
							(start 0.254 -0.1778)
							(mid 0.239121 -0.213721)
							(end 0.2032 -0.2286)
						)
						(arc
							(start -0.2032 -0.2286)
							(mid -0.239121 -0.213721)
							(end -0.254 -0.1778)
						)
					)
					(width 0)
					(fill yes)
				)
			)
		)
	)
	(footprint ""
		(layer "B.Cu")
		(at 100.33 -68.326 180)
		(property "Reference" "PC122"
			(at 0 0 0)
			(layer "B.SilkS")
			(hide yes)
			(effects
				(font
					(size 1.27 1.27)
				)
				(justify mirror)
			)
		)
		(property "Value" "SCD015U25V2KX-GP"
			(at -1.1811 -2.7051 180)
			(unlocked yes)
			(layer "B.Fab")
			(hide yes)
			(effects
				(font
					(size 1.016 1.016)
					(thickness 0.1524)
				)
				(justify mirror)
			)
		)
		(property "Device Type" "C402H22"
			(at -1.1811 -4.2291 180)
			(unlocked yes)
			(layer "B.Fab")
			(hide yes)
			(effects
				(font
					(size 1.016 1.016)
					(thickness 0.1524)
				)
				(justify mirror)
			)
		)
		(duplicate_pad_numbers_are_jumpers no)
		(fp_rect
			(start 0.381 0.7366)
			(end -0.381 -0.7366)
			(stroke
				(width 0)
				(type default)
			)
			(fill no)
			(layer "B.CrtYd")
		)
		(fp_rect
			(start 0.381 0.7366)
			(end -0.381 -0.7366)
			(stroke
				(width 0)
				(type default)
			)
			(fill no)
			(layer "B.Fab")
		)
		(pad "1" smd custom
			(at 0 -0.4572)
			(size 0.1143 0.1143)
			(layers "B.Cu" "B.Mask" "B.Paste")
			(net "VR_P1V1_SS")
			(options
				(clearance outline)
				(anchor circle)
			)
			(primitives
				(gr_poly
					(pts
						(arc
							(start -0.254 0.1778)
							(mid -0.239121 0.213721)
							(end -0.2032 0.2286)
						)
						(arc
							(start 0.2032 0.2286)
							(mid 0.239121 0.213721)
							(end 0.254 0.1778)
						)
						(arc
							(start 0.254 -0.1778)
							(mid 0.239121 -0.213721)
							(end 0.2032 -0.2286)
						)
						(arc
							(start -0.2032 -0.2286)
							(mid -0.239121 -0.213721)
							(end -0.254 -0.1778)
						)
					)
					(width 0)
					(fill yes)
				)
			)
		)
		(pad "2" smd custom
			(at 0 0.4572)
			(size 0.1143 0.1143)
			(layers "B.Cu" "B.Mask" "B.Paste")
			(net "GND")
			(options
				(clearance outline)
				(anchor circle)
			)
			(primitives
				(gr_poly
					(pts
						(arc
							(start -0.254 0.1778)
							(mid -0.239121 0.213721)
							(end -0.2032 0.2286)
						)
						(arc
							(start 0.2032 0.2286)
							(mid 0.239121 0.213721)
							(end 0.254 0.1778)
						)
						(arc
							(start 0.254 -0.1778)
							(mid 0.239121 -0.213721)
							(end 0.2032 -0.2286)
						)
						(arc
							(start -0.2032 -0.2286)
							(mid -0.239121 -0.213721)
							(end -0.254 -0.1778)
						)
					)
					(width 0)
					(fill yes)
				)
			)
		)
	)
)
